G04*
G04 #@! TF.GenerationSoftware,Altium Limited,Altium Designer,23.6.0 (18)*
G04*
G04 Layer_Color=128*
%FSLAX44Y44*%
%MOMM*%
G71*
G04*
G04 #@! TF.SameCoordinates,B62FFF2A-40BB-47C2-B022-6C0D6E2DF31E*
G04*
G04*
G04 #@! TF.FilePolarity,Positive*
G04*
G01*
G75*
%ADD67R,0.3500X1.9500*%
D67*
X140060Y15250D02*
D03*
X135060D02*
D03*
X130060D02*
D03*
X125060D02*
D03*
X120060D02*
D03*
X115060D02*
D03*
X110060D02*
D03*
X155060D02*
D03*
X150060D02*
D03*
X80060D02*
D03*
X90060D02*
D03*
X85060D02*
D03*
X95060D02*
D03*
X75060D02*
D03*
X70060D02*
D03*
X65060D02*
D03*
X60060D02*
D03*
X55060D02*
D03*
X50060D02*
D03*
X45060D02*
D03*
X40060D02*
D03*
X35060D02*
D03*
X30060D02*
D03*
X25060D02*
D03*
X100060D02*
D03*
X105060D02*
D03*
X145060D02*
D03*
X185060D02*
D03*
X200060D02*
D03*
X195060D02*
D03*
X190060D02*
D03*
X180060D02*
D03*
X20060D02*
D03*
M02*
